# T6G (Grand Teton) — schematic netlist excerpt (pin names and nets, part order shuffled) for the footprints in the layout excerpt that follows; sources: Cadence DE-HDL packaged netlist, KiCad conversion of 04192023_DAF0TMB3IC0_F0TG_MB_C_brd_V02_OCP.brd

PR333  Q_RES  0 5% CHIP  pkg 0402LF  page 225 : A = PVDD11_S3_P1_VOS2 ; B = PVDD11_S3_P1
PC563_4  Q_CAP  22UF 4V 20% X6S  pkg C0805  page 195 : A = PVDDCR_CPU0_P0 ; B = GND
R9275  Q_RES  0 5% CHIP  pkg 0402LF  page 28 : A = CLK_100M_CPU0_CLK05_R_DP ; B = CLK_100M_CPU0_CLK05_DP

(kicad_pcb
	(version 20260206)
	(generator "pcbnew")
	(generator_version "10.0")
	(general
		(thickness 1.6)
		(legacy_teardrops no)
	)
	(paper "A4")
	(title_block
		(title "04192023_DAF0TMB3IC0_F0TG_MB_C_brd_V02_OCP.brd")
		(comment 1 "Grand Teton / footprints 7548-7550 of 8354")
	)
	(layers
		(0 "F.Cu" signal "TOP")
		(4 "In1.Cu" signal "GND")
		(6 "In2.Cu" signal "IN1")
		(8 "In3.Cu" signal "GND1")
		(10 "In4.Cu" signal "IN2")
		(12 "In5.Cu" signal "GND2")
		(14 "In6.Cu" signal "IN3")
		(16 "In7.Cu" signal "GND3")
		(18 "In8.Cu" signal "VCC")
		(20 "In9.Cu" signal "VCC1")
		(22 "In10.Cu" signal "GND4")
		(24 "In11.Cu" signal "IN4")
		(26 "In12.Cu" signal "GND5")
		(28 "In13.Cu" signal "IN5")
		(30 "In14.Cu" signal "GND6")
		(32 "In15.Cu" signal "IN6")
		(34 "In16.Cu" signal "GND7")
		(2 "B.Cu" signal "BOTTOM")
		(9 "F.Adhes" user "F.Adhesive")
		(11 "B.Adhes" user "B.Adhesive")
		(13 "F.Paste" user "Package Geometry/Pastemask Top")
		(15 "B.Paste" user "Package Geometry/Pastemask Bottom")
		(5 "F.SilkS" user "Ref Des/Silkscreen Top")
		(7 "B.SilkS" user "Ref Des/Silkscreen Bottom")
		(1 "F.Mask" user "Board Geometry/Soldermask Top")
		(3 "B.Mask" user "Board Geometry/Soldermask Bottom")
		(17 "Dwgs.User" user "User.Drawings")
		(19 "Cmts.User" user "User.Comments")
		(21 "Eco1.User" user "User.Eco1")
		(23 "Eco2.User" user "User.Eco2")
		(25 "Edge.Cuts" user "Board Geometry/Outline")
		(27 "Margin" user)
		(31 "F.CrtYd" user "Package Geometry/Place Bound Top")
		(29 "B.CrtYd" user "Package Geometry/Place Bound Bottom")
		(35 "F.Fab" user "Ref Des/Assembly Top")
		(33 "B.Fab" user "Ref Des/Assembly Bottom")
	)
	(footprint ""
		(layer "B.Cu")
		(at 187.585096 -353.986084 -90)
		(property "Reference" "PR333"
			(at 0 0 90)
			(layer "B.SilkS")
			(hide yes)
			(effects
				(font
					(size 1.27 1.27)
				)
				(justify mirror)
			)
		)
		(property "Value" ""
			(at 0 0 90)
			(layer "B.Fab")
			(effects
				(font
					(size 1.27 1.27)
				)
				(justify mirror)
			)
		)
		(duplicate_pad_numbers_are_jumpers no)
		(fp_line
			(start -0.7874 0.4064)
			(end 0.7874 0.4064)
			(stroke
				(width 0.1524)
				(type default)
			)
			(layer "B.SilkS")
		)
		(fp_line
			(start 0.7874 0.4064)
			(end 0.7874 -0.4064)
			(stroke
				(width 0.1524)
				(type default)
			)
			(layer "B.SilkS")
		)
		(fp_line
			(start -0.7874 -0.4064)
			(end -0.7874 0.4064)
			(stroke
				(width 0.1524)
				(type default)
			)
			(layer "B.SilkS")
		)
		(fp_line
			(start 0.7874 -0.4064)
			(end -0.7874 -0.4064)
			(stroke
				(width 0.1524)
				(type default)
			)
			(layer "B.SilkS")
		)
		(fp_line
			(start -0.67945 0.3048)
			(end -0.120396 0.3048)
			(stroke
				(width 0.1)
				(type default)
			)
			(layer "B.Fab")
		)
		(fp_line
			(start -0.120396 0.3048)
			(end -0.120396 0.2794)
			(stroke
				(width 0.1)
				(type default)
			)
			(layer "B.Fab")
		)
		(fp_line
			(start 0.12065 0.3048)
			(end 0.67945 0.3048)
			(stroke
				(width 0.1)
				(type default)
			)
			(layer "B.Fab")
		)
		(fp_line
			(start 0.67945 0.3048)
			(end 0.67945 -0.305054)
			(stroke
				(width 0.1)
				(type default)
			)
			(layer "B.Fab")
		)
		(fp_line
			(start -0.120396 0.2794)
			(end 0.12065 0.2794)
			(stroke
				(width 0.1)
				(type default)
			)
			(layer "B.Fab")
		)
		(fp_line
			(start 0.12065 0.2794)
			(end 0.12065 0.3048)
			(stroke
				(width 0.1)
				(type default)
			)
			(layer "B.Fab")
		)
		(fp_line
			(start -0.12065 -0.2794)
			(end -0.12065 -0.3048)
			(stroke
				(width 0.1)
				(type default)
			)
			(layer "B.Fab")
		)
		(fp_line
			(start 0.12065 -0.2794)
			(end -0.12065 -0.2794)
			(stroke
				(width 0.1)
				(type default)
			)
			(layer "B.Fab")
		)
		(fp_line
			(start -0.67945 -0.3048)
			(end -0.67945 0.3048)
			(stroke
				(width 0.1)
				(type default)
			)
			(layer "B.Fab")
		)
		(fp_line
			(start -0.12065 -0.3048)
			(end -0.67945 -0.3048)
			(stroke
				(width 0.1)
				(type default)
			)
			(layer "B.Fab")
		)
		(fp_line
			(start 0.12065 -0.305054)
			(end 0.12065 -0.2794)
			(stroke
				(width 0.1)
				(type default)
			)
			(layer "B.Fab")
		)
		(fp_line
			(start 0.67945 -0.305054)
			(end 0.12065 -0.305054)
			(stroke
				(width 0.1)
				(type default)
			)
			(layer "B.Fab")
		)
		(pad "1" smd circle
			(at 0.40005 0 90)
			(size 0 0)
			(layers "B.Cu" "B.Mask" "B.Paste")
			(net "PVDD11_S3_P1_VOS2")
		)
		(pad "2" smd circle
			(at -0.40005 0 90)
			(size 0 0)
			(layers "B.Cu" "B.Mask" "B.Paste")
			(net "PVDD11_S3_P1")
		)
	)
	(footprint ""
		(layer "B.Cu")
		(at 378.957586 -214.523828 90)
		(property "Reference" "R9275"
			(at 0 0 90)
			(layer "B.SilkS")
			(hide yes)
			(effects
				(font
					(size 1.27 1.27)
				)
				(justify mirror)
			)
		)
		(property "Value" ""
			(at 0 0 90)
			(layer "B.Fab")
			(effects
				(font
					(size 1.27 1.27)
				)
				(justify mirror)
			)
		)
		(duplicate_pad_numbers_are_jumpers no)
		(fp_line
			(start 0.360172 -0.4064)
			(end -0.376428 -0.4064)
			(stroke
				(width 0.1524)
				(type default)
			)
			(layer "B.SilkS")
		)
		(fp_line
			(start -0.7874 0.086614)
			(end -0.7874 0.4064)
			(stroke
				(width 0.1524)
				(type default)
			)
			(layer "B.SilkS")
		)
		(fp_line
			(start 0.7874 0.4064)
			(end 0.7874 0.010414)
			(stroke
				(width 0.1524)
				(type default)
			)
			(layer "B.SilkS")
		)
		(fp_line
			(start -0.7874 0.4064)
			(end 0.7874 0.4064)
			(stroke
				(width 0.1524)
				(type default)
			)
			(layer "B.SilkS")
		)
		(fp_line
			(start 0.67945 -0.305054)
			(end 0.12065 -0.305054)
			(stroke
				(width 0.1)
				(type default)
			)
			(layer "B.Fab")
		)
		(fp_line
			(start 0.12065 -0.305054)
			(end 0.12065 -0.2794)
			(stroke
				(width 0.1)
				(type default)
			)
			(layer "B.Fab")
		)
		(fp_line
			(start -0.12065 -0.3048)
			(end -0.67945 -0.3048)
			(stroke
				(width 0.1)
				(type default)
			)
			(layer "B.Fab")
		)
		(fp_line
			(start -0.67945 -0.3048)
			(end -0.67945 0.3048)
			(stroke
				(width 0.1)
				(type default)
			)
			(layer "B.Fab")
		)
		(fp_line
			(start 0.12065 -0.2794)
			(end -0.12065 -0.2794)
			(stroke
				(width 0.1)
				(type default)
			)
			(layer "B.Fab")
		)
		(fp_line
			(start -0.12065 -0.2794)
			(end -0.12065 -0.3048)
			(stroke
				(width 0.1)
				(type default)
			)
			(layer "B.Fab")
		)
		(fp_line
			(start 0.12065 0.2794)
			(end 0.12065 0.3048)
			(stroke
				(width 0.1)
				(type default)
			)
			(layer "B.Fab")
		)
		(fp_line
			(start -0.120396 0.2794)
			(end 0.12065 0.2794)
			(stroke
				(width 0.1)
				(type default)
			)
			(layer "B.Fab")
		)
		(fp_line
			(start 0.67945 0.3048)
			(end 0.67945 -0.305054)
			(stroke
				(width 0.1)
				(type default)
			)
			(layer "B.Fab")
		)
		(fp_line
			(start 0.12065 0.3048)
			(end 0.67945 0.3048)
			(stroke
				(width 0.1)
				(type default)
			)
			(layer "B.Fab")
		)
		(fp_line
			(start -0.120396 0.3048)
			(end -0.120396 0.2794)
			(stroke
				(width 0.1)
				(type default)
			)
			(layer "B.Fab")
		)
		(fp_line
			(start -0.67945 0.3048)
			(end -0.120396 0.3048)
			(stroke
				(width 0.1)
				(type default)
			)
			(layer "B.Fab")
		)
		(pad "1" smd circle
			(at 0.40005 0 270)
			(size 0 0)
			(layers "B.Cu" "B.Mask" "B.Paste")
			(net "CLK_100M_CPU0_CLK05_R_DP")
		)
		(pad "2" smd circle
			(at -0.40005 0 270)
			(size 0 0)
			(layers "B.Cu" "B.Mask" "B.Paste")
			(net "CLK_100M_CPU0_CLK05_DP")
		)
	)
	(footprint ""
		(layer "B.Cu")
		(at 392.695938 -195.830952 90)
		(property "Reference" "PC563_4"
			(at 0 0 90)
			(layer "B.SilkS")
			(hide yes)
			(effects
				(font
					(size 1.27 1.27)
				)
				(justify mirror)
			)
		)
		(property "Value" ""
			(at 0 0 90)
			(layer "B.Fab")
			(effects
				(font
					(size 1.27 1.27)
				)
				(justify mirror)
			)
		)
		(duplicate_pad_numbers_are_jumpers no)
		(fp_line
			(start 1.524 -0.762)
			(end -1.524 -0.762)
			(stroke
				(width 0.1524)
				(type default)
			)
			(layer "B.SilkS")
		)
		(fp_line
			(start -1.524 -0.762)
			(end -1.524 0.762)
			(stroke
				(width 0.1524)
				(type default)
			)
			(layer "B.SilkS")
		)
		(fp_line
			(start 1.524 0.762)
			(end 1.524 -0.762)
			(stroke
				(width 0.1524)
				(type default)
			)
			(layer "B.SilkS")
		)
		(fp_line
			(start -1.524 0.762)
			(end 1.524 0.762)
			(stroke
				(width 0.1524)
				(type default)
			)
			(layer "B.SilkS")
		)
		(fp_line
			(start 1.1049 -0.724916)
			(end 1.1049 0.724916)
			(stroke
				(width 0.1)
				(type default)
			)
			(layer "B.Fab")
		)
		(fp_line
			(start -1.1049 -0.724916)
			(end 1.1049 -0.724916)
			(stroke
				(width 0.1)
				(type default)
			)
			(layer "B.Fab")
		)
		(fp_line
			(start 1.1049 0.724916)
			(end -1.1049 0.724916)
			(stroke
				(width 0.1)
				(type default)
			)
			(layer "B.Fab")
		)
		(fp_line
			(start -1.1049 0.724916)
			(end -1.1049 -0.724916)
			(stroke
				(width 0.1)
				(type default)
			)
			(layer "B.Fab")
		)
		(pad "1" smd rect
			(at 0.889 0 90)
			(size 1.016 1.27)
			(layers "B.Cu" "B.Mask" "B.Paste")
			(net "PVDDCR_CPU0_P0")
		)
		(pad "2" smd rect
			(at -0.889 0 90)
			(size 1.016 1.27)
			(layers "B.Cu" "B.Mask" "B.Paste")
			(net "GND")
		)
	)
)
